# S9S_MB_2U (Grand Teton) — schematic netlist excerpt (pin names and nets, part order shuffled) for the footprints in the layout excerpt that follows; sources: Cadence DE-HDL packaged netlist, KiCad conversion of 03242023_DA0F0TMBIJ0_F0T_Motherboard_J_brd_V01_OCP.brd

C444  Q_CAP  22UF 4V 20% X6S  pkg C0402  page 77 : A = PVCCFA_EHV_CPU1 ; B = GND
H101  HOLE  EMPTY  pkg TH  page 311 : \1\ = GND
R1700  Q_RES  200K 1% CHIP  pkg 0402LF  page 194 : A = P3V3_AUX ; B = SMB_PCIE_M2_0_EN
H25  HOLE  EMPTY  pkg TH  page 311 : \1\ = NC

(kicad_pcb
	(version 20260206)
	(generator "pcbnew")
	(generator_version "10.0")
	(general
		(thickness 1.6)
		(legacy_teardrops no)
	)
	(paper "A4")
	(title_block
		(title "03242023_DA0F0TMBIJ0_F0T_Motherboard_J_brd_V01_OCP.brd")
		(comment 1 "Grand Teton / footprints 850-853 of 6105")
	)
	(layers
		(0 "F.Cu" signal "TOP")
		(4 "In1.Cu" signal "GND")
		(6 "In2.Cu" signal "IN1")
		(8 "In3.Cu" signal "GND1")
		(10 "In4.Cu" signal "IN2")
		(12 "In5.Cu" signal "GND2")
		(14 "In6.Cu" signal "IN3")
		(16 "In7.Cu" signal "GND3")
		(18 "In8.Cu" signal "VCC")
		(20 "In9.Cu" signal "VCC1")
		(22 "In10.Cu" signal "GND4")
		(24 "In11.Cu" signal "IN4")
		(26 "In12.Cu" signal "GND5")
		(28 "In13.Cu" signal "IN5")
		(30 "In14.Cu" signal "GND6")
		(32 "In15.Cu" signal "IN6")
		(34 "In16.Cu" signal "GND7")
		(2 "B.Cu" signal "BOTTOM")
		(9 "F.Adhes" user "F.Adhesive")
		(11 "B.Adhes" user "B.Adhesive")
		(13 "F.Paste" user "Package Geometry/Pastemask Top")
		(15 "B.Paste" user "Package Geometry/Pastemask Bottom")
		(5 "F.SilkS" user "Ref Des/Silkscreen Top")
		(7 "B.SilkS" user "Ref Des/Silkscreen Bottom")
		(1 "F.Mask" user "Board Geometry/Soldermask Top")
		(3 "B.Mask" user "Board Geometry/Soldermask Bottom")
		(17 "Dwgs.User" user "User.Drawings")
		(19 "Cmts.User" user "User.Comments")
		(21 "Eco1.User" user "User.Eco1")
		(23 "Eco2.User" user "User.Eco2")
		(25 "Edge.Cuts" user "Board Geometry/Outline")
		(27 "Margin" user)
		(31 "F.CrtYd" user "Package Geometry/Place Bound Top")
		(29 "B.CrtYd" user "Package Geometry/Place Bound Bottom")
		(35 "F.Fab" user "Ref Des/Assembly Top")
		(33 "B.Fab" user "Ref Des/Assembly Bottom")
	)
	(footprint ""
		(layer "F.Cu")
		(at 159.82188 -58.511948 180)
		(property "Reference" "R1700"
			(at 0 0 180)
			(layer "F.SilkS")
			(hide yes)
			(effects
				(font
					(size 1.27 1.27)
				)
			)
		)
		(property "Value" ""
			(at 0 0 180)
			(layer "F.Fab")
			(effects
				(font
					(size 1.27 1.27)
				)
			)
		)
		(duplicate_pad_numbers_are_jumpers no)
		(fp_line
			(start 0.7874 0.4064)
			(end -0.7874 0.4064)
			(stroke
				(width 0.1524)
				(type default)
			)
			(layer "F.SilkS")
		)
		(fp_line
			(start 0.7874 -0.4064)
			(end 0.7874 0.4064)
			(stroke
				(width 0.1524)
				(type default)
			)
			(layer "F.SilkS")
		)
		(fp_line
			(start -0.7874 0.4064)
			(end -0.7874 -0.4064)
			(stroke
				(width 0.1524)
				(type default)
			)
			(layer "F.SilkS")
		)
		(fp_line
			(start -0.7874 -0.4064)
			(end 0.7874 -0.4064)
			(stroke
				(width 0.1524)
				(type default)
			)
			(layer "F.SilkS")
		)
		(fp_line
			(start 0.67945 0.3048)
			(end 0.120396 0.3048)
			(stroke
				(width 0.1)
				(type default)
			)
			(layer "F.Fab")
		)
		(fp_line
			(start 0.67945 -0.3048)
			(end 0.67945 0.3048)
			(stroke
				(width 0.1)
				(type default)
			)
			(layer "F.Fab")
		)
		(fp_line
			(start 0.12065 -0.2794)
			(end 0.12065 -0.3048)
			(stroke
				(width 0.1)
				(type default)
			)
			(layer "F.Fab")
		)
		(fp_line
			(start 0.12065 -0.3048)
			(end 0.67945 -0.3048)
			(stroke
				(width 0.1)
				(type default)
			)
			(layer "F.Fab")
		)
		(fp_line
			(start 0.120396 0.3048)
			(end 0.120396 0.2794)
			(stroke
				(width 0.1)
				(type default)
			)
			(layer "F.Fab")
		)
		(fp_line
			(start 0.120396 0.2794)
			(end -0.12065 0.2794)
			(stroke
				(width 0.1)
				(type default)
			)
			(layer "F.Fab")
		)
		(fp_line
			(start -0.12065 0.3048)
			(end -0.67945 0.3048)
			(stroke
				(width 0.1)
				(type default)
			)
			(layer "F.Fab")
		)
		(fp_line
			(start -0.12065 0.2794)
			(end -0.12065 0.3048)
			(stroke
				(width 0.1)
				(type default)
			)
			(layer "F.Fab")
		)
		(fp_line
			(start -0.12065 -0.2794)
			(end 0.12065 -0.2794)
			(stroke
				(width 0.1)
				(type default)
			)
			(layer "F.Fab")
		)
		(fp_line
			(start -0.12065 -0.305054)
			(end -0.12065 -0.2794)
			(stroke
				(width 0.1)
				(type default)
			)
			(layer "F.Fab")
		)
		(fp_line
			(start -0.67945 0.3048)
			(end -0.67945 -0.305054)
			(stroke
				(width 0.1)
				(type default)
			)
			(layer "F.Fab")
		)
		(fp_line
			(start -0.67945 -0.305054)
			(end -0.12065 -0.305054)
			(stroke
				(width 0.1)
				(type default)
			)
			(layer "F.Fab")
		)
		(pad "1" smd circle
			(at -0.40005 0 180)
			(size 0 0)
			(layers "F.Cu" "F.Mask" "F.Paste")
			(net "P3V3_AUX")
		)
		(pad "2" smd circle
			(at 0.40005 0 180)
			(size 0 0)
			(layers "F.Cu" "F.Mask" "F.Paste")
			(net "SMB_PCIE_M2_0_EN")
		)
	)
	(footprint ""
		(layer "F.Cu")
		(at 325.860156 -251.76988)
		(property "Reference" "H25"
			(at -5.439156 -4.581398 0)
			(unlocked yes)
			(layer "F.SilkS")
			(effects
				(font
					(size 0.7874 0.5842)
					(thickness 0.1524)
				)
				(justify left)
			)
		)
		(property "Value" ""
			(at 0 0 0)
			(layer "F.Fab")
			(effects
				(font
					(size 1.27 1.27)
				)
			)
		)
		(duplicate_pad_numbers_are_jumpers no)
		(fp_circle
			(center 0 0)
			(end 2.5273 0)
			(stroke
				(width 0.1524)
				(type default)
			)
			(fill no)
			(layer "F.SilkS")
		)
		(fp_circle
			(center 0 0)
			(end 2.5273 0)
			(stroke
				(width 0.1524)
				(type default)
			)
			(fill no)
			(layer "B.SilkS")
		)
		(fp_circle
			(center 0 0)
			(end 2.5273 0)
			(stroke
				(width 0.1)
				(type default)
			)
			(fill no)
			(layer "B.Fab")
		)
		(fp_circle
			(center 0 0)
			(end 2.5273 0)
			(stroke
				(width 0.1)
				(type default)
			)
			(fill no)
			(layer "F.Fab")
		)
		(pad "" np_thru_hole circle
			(at 0 0)
			(size 3.429 3.429)
			(drill 3.429)
			(layers "*.Cu" "*.Mask")
			(clearance 0.381)
			(thermal_gap 0.381)
		)
	)
	(footprint ""
		(layer "F.Cu")
		(at 104.347264 -258.72694 90)
		(property "Reference" "C444"
			(at 0 0 90)
			(layer "F.SilkS")
			(hide yes)
			(effects
				(font
					(size 1.27 1.27)
				)
			)
		)
		(property "Value" ""
			(at 0 0 90)
			(layer "F.Fab")
			(effects
				(font
					(size 1.27 1.27)
				)
			)
		)
		(duplicate_pad_numbers_are_jumpers no)
		(fp_line
			(start 0.7874 -0.4064)
			(end 0.7874 0.4064)
			(stroke
				(width 0.1524)
				(type default)
			)
			(layer "F.SilkS")
		)
		(fp_line
			(start -0.7874 -0.4064)
			(end 0.7874 -0.4064)
			(stroke
				(width 0.1524)
				(type default)
			)
			(layer "F.SilkS")
		)
		(fp_line
			(start 0.7874 0.4064)
			(end -0.7874 0.4064)
			(stroke
				(width 0.1524)
				(type default)
			)
			(layer "F.SilkS")
		)
		(fp_line
			(start -0.7874 0.4064)
			(end -0.7874 -0.4064)
			(stroke
				(width 0.1524)
				(type default)
			)
			(layer "F.SilkS")
		)
		(fp_line
			(start -0.12065 -0.305054)
			(end -0.12065 -0.2794)
			(stroke
				(width 0.1)
				(type default)
			)
			(layer "F.Fab")
		)
		(fp_line
			(start -0.67945 -0.305054)
			(end -0.12065 -0.305054)
			(stroke
				(width 0.1)
				(type default)
			)
			(layer "F.Fab")
		)
		(fp_line
			(start 0.67945 -0.3048)
			(end 0.67945 0.3048)
			(stroke
				(width 0.1)
				(type default)
			)
			(layer "F.Fab")
		)
		(fp_line
			(start 0.12065 -0.3048)
			(end 0.67945 -0.3048)
			(stroke
				(width 0.1)
				(type default)
			)
			(layer "F.Fab")
		)
		(fp_line
			(start 0.12065 -0.2794)
			(end 0.12065 -0.3048)
			(stroke
				(width 0.1)
				(type default)
			)
			(layer "F.Fab")
		)
		(fp_line
			(start -0.12065 -0.2794)
			(end 0.12065 -0.2794)
			(stroke
				(width 0.1)
				(type default)
			)
			(layer "F.Fab")
		)
		(fp_line
			(start 0.120396 0.2794)
			(end -0.12065 0.2794)
			(stroke
				(width 0.1)
				(type default)
			)
			(layer "F.Fab")
		)
		(fp_line
			(start -0.12065 0.2794)
			(end -0.12065 0.3048)
			(stroke
				(width 0.1)
				(type default)
			)
			(layer "F.Fab")
		)
		(fp_line
			(start 0.67945 0.3048)
			(end 0.120396 0.3048)
			(stroke
				(width 0.1)
				(type default)
			)
			(layer "F.Fab")
		)
		(fp_line
			(start 0.120396 0.3048)
			(end 0.120396 0.2794)
			(stroke
				(width 0.1)
				(type default)
			)
			(layer "F.Fab")
		)
		(fp_line
			(start -0.12065 0.3048)
			(end -0.67945 0.3048)
			(stroke
				(width 0.1)
				(type default)
			)
			(layer "F.Fab")
		)
		(fp_line
			(start -0.67945 0.3048)
			(end -0.67945 -0.305054)
			(stroke
				(width 0.1)
				(type default)
			)
			(layer "F.Fab")
		)
		(pad "1" smd circle
			(at -0.40005 0 90)
			(size 0 0)
			(layers "F.Cu" "F.Mask" "F.Paste")
			(net "PVCCFA_EHV_CPU1")
		)
		(pad "2" smd circle
			(at 0.40005 0 90)
			(size 0 0)
			(layers "F.Cu" "F.Mask" "F.Paste")
			(net "GND")
		)
	)
	(footprint ""
		(layer "F.Cu")
		(at 94.899988 -22.29993)
		(property "Reference" "H101"
			(at -6.23824 -4.478528 0)
			(unlocked yes)
			(layer "F.SilkS")
			(effects
				(font
					(size 0.7874 0.5842)
					(thickness 0.1524)
				)
				(justify left)
			)
		)
		(property "Value" ""
			(at 0 0 0)
			(layer "F.Fab")
			(effects
				(font
					(size 1.27 1.27)
				)
			)
		)
		(duplicate_pad_numbers_are_jumpers no)
		(pad "1" thru_hole circle
			(at 0 0)
			(size 10.0076 10.0076)
			(drill 5.6134)
			(layers "*.Cu" "*.Mask")
			(remove_unused_layers no)
			(net "GND")
			(clearance -1.9431)
		)
	)
)
